# T6G (Grand Teton) — schematic netlist excerpt (pin names and nets, part order shuffled) for the footprints in the layout excerpt that follows; sources: Cadence DE-HDL packaged netlist, KiCad conversion of 04192023_DAF0TMB3IC0_F0TG_MB_C_brd_V02_OCP.brd

J20  SCONN288_DDR506112002KQ  IO  pkg DDR288S_1-1VXC  page 96
  VIN_BULK0  = P12V_MEM_CPU0
  RFU0  = NC
  VIN_MGMT  = P3V3_AUX
  HSCL  = I3C_SPD_DDRK_CPU0_SCL
  HSDA  = I3C_SPD_DDRK_CPU0_SDA
  VSS0  = GND
  DQ0_A  = M_K_CPU0_SA_DQ<0>
  VSS1  = GND
  DQ1_A  = M_K_CPU0_SA_DQ<1>
  VSS2  = GND
  DQS0_A_T  = M_K_CPU0_SA_DQS_DP<0>
  DQS0_A_C  = M_K_CPU0_SA_DQS_DN<0>
  VSS3  = GND
  DQ4_A  = M_K_CPU0_SA_DQ<4>
  VSS4  = GND
  DQ5_A  = M_K_CPU0_SA_DQ<5>
  VSS5  = GND
  DQ8_A  = M_K_CPU0_SA_DQ<8>
  VSS6  = GND
  DQ9_A  = M_K_CPU0_SA_DQ<9>
  VSS7  = GND
  DQS1_A_T  = M_K_CPU0_SA_DQS_DP<1>
  DQS1_A_C  = M_K_CPU0_SA_DQS_DN<1>
  VSS8  = GND
  DQ12_A  = M_K_CPU0_SA_DQ<12>
  VSS9  = GND
  DQ13_A  = M_K_CPU0_SA_DQ<13>
  VSS10  = GND
  DQ16_A  = M_K_CPU0_SA_DQ<16>
  VSS11  = GND
  DQ17_A  = M_K_CPU0_SA_DQ<17>
  VSS12  = GND
  DQS2_A_T  = M_K_CPU0_SA_DQS_DP<2>
  DQS2_A_C  = M_K_CPU0_SA_DQS_DN<2>
  VSS13  = GND
  DQ20_A  = M_K_CPU0_SA_DQ<20>
  VSS14  = GND
  DQ21_A  = M_K_CPU0_SA_DQ<21>
  VSS15  = GND
  DQ24_A  = M_K_CPU0_SA_DQ<24>
  VSS16  = GND
  DQ25_A  = M_K_CPU0_SA_DQ<25>
  VSS17  = GND
  DQS3_A_T  = M_K_CPU0_SA_DQS_DP<3>
  DQS3_A_C  = M_K_CPU0_SA_DQS_DN<3>
  VSS18  = GND
  DQ28_A  = M_K_CPU0_SA_DQ<28>
  VSS19  = GND
  DQ29_A  = M_K_CPU0_SA_DQ<29>
  VSS20  = GND
  CB0_A  = M_K_CPU0_SA_CB<0>
  VSS21  = GND
  CB1_A  = M_K_CPU0_SA_CB<1>
  VSS22  = GND
  DQS4_A_T  = M_K_CPU0_SA_DQS_DP<4>
  DQS4_A_C  = M_K_CPU0_SA_DQS_DN<4>
  VSS23  = GND
  CB4_A  = M_K_CPU0_SA_CB<4>
  VSS24  = GND
  CB5_A  = M_K_CPU0_SA_CB<5>
  VSS25  = GND
  ALERT_N  = M_K_CPU0_ALERT_N
  VSS26  = GND
  CS0_A_N  = M_K_CPU0_SA_CS_N<0>
  VSS27  = GND
  CA0_A  = M_K_CPU0_SA_CA<0>
  VSS28  = GND
  CA2_A  = M_K_CPU0_SA_CA<2>
  VSS29  = GND
  CA4_A  = M_K_CPU0_SA_CA<4>
  VSS30  = GND
  CA6_A  = M_K_CPU0_SA_CA<6>
  VSS31  = GND
  PAR_A  = M_K_CPU0_SA_PAR
  VSS32  = GND
  CA0_B  = M_K_CPU0_SB_CA<0>
  VSS33  = GND
  CA2_B  = M_K_CPU0_SB_CA<2>
  VSS34  = GND
  CA4_B  = M_K_CPU0_SB_CA<4>
  VSS35  = GND
  CA6_B  = M_K_CPU0_SB_CA<6>
  VSS36  = GND
  CS0_B_N  = M_K_CPU0_SB_CS_N<0>
  VSS37  = GND
  \lbd||rsp_a_n\  = M_K_CPU0_SA_RSP<0>
  \lbs||rsp_b_n\  = M_K_CPU0_SB_RSP<0>
  VSS38  = GND
  CB4_B  = M_K_CPU0_SB_CB<4>
  VSS39  = GND
  CB5_B  = M_K_CPU0_SB_CB<5>
  VSS40  = GND
  \dqs9_b_t||tdqs9_b_t||dbi4_b_n\  = M_K_CPU0_SB_DQS_DP<9>
  \dqs9_b_c||tdqs9_b_c\  = M_K_CPU0_SB_DQS_DN<9>
  VSS41  = GND
  CB0_B  = M_K_CPU0_SB_CB<0>
  VSS42  = GND
  CB1_B  = M_K_CPU0_SB_CB<1>
  VSS43  = GND
  DQ0_B  = M_K_CPU0_SB_DQ<0>
  VSS44  = GND
  DQ1_B  = M_K_CPU0_SB_DQ<1>
  VSS45  = GND
  DQS0_B_T  = M_K_CPU0_SB_DQS_DP<0>
  DQS0_B_C  = M_K_CPU0_SB_DQS_DN<0>
  VSS46  = GND
  DQ4_B  = M_K_CPU0_SB_DQ<4>
  VSS47  = GND
  DQ5_B  = M_K_CPU0_SB_DQ<5>
  VSS48  = GND
  DQ8_B  = M_K_CPU0_SB_DQ<8>
  VSS49  = GND
  DQ9_B  = M_K_CPU0_SB_DQ<9>
  VSS50  = GND
  DQS1_B_T  = M_K_CPU0_SB_DQS_DP<1>
  DQS1_B_C  = M_K_CPU0_SB_DQS_DN<1>
  VSS51  = GND
  DQ12_B  = M_K_CPU0_SB_DQ<12>
  VSS52  = GND
  DQ13_B  = M_K_CPU0_SB_DQ<13>
  VSS53  = GND
  DQ16_B  = M_K_CPU0_SB_DQ<16>
  VSS54  = GND
  DQ17_B  = M_K_CPU0_SB_DQ<17>
  VSS55  = GND
  DQS2_B_T  = M_K_CPU0_SB_DQS_DP<2>
  DQS2_B_C  = M_K_CPU0_SB_DQS_DN<2>
  VSS56  = GND
  DQ20_B  = M_K_CPU0_SB_DQ<20>
  VSS57  = GND
  DQ21_B  = M_K_CPU0_SB_DQ<21>
  VSS58  = GND
  DQ24_B  = M_K_CPU0_SB_DQ<24>
  VSS59  = GND
  DQ25_B  = M_K_CPU0_SB_DQ<25>
  VSS60  = GND
  DQS3_B_T  = M_K_CPU0_SB_DQS_DP<3>
  DQS3_B_C  = M_K_CPU0_SB_DQS_DN<3>
  VSS61  = GND
  DQ28_B  = M_K_CPU0_SB_DQ<28>
  VSS62  = GND
  DQ29_B  = M_K_CPU0_SB_DQ<29>
  VSS63  = GND
  RFU1  = NC
  VIN_BULK1  = P12V_MEM_CPU0
  VIN_BULK2  = P12V_MEM_CPU0
  \pwr_good||fail_n\  = PWRGD_CHK_CPU0_DIMM
  HAS  = PD_CHK_CPU0_DIMM_SAA
  RFU2  = NC
  RFU3  = NC
  VSS64  = GND
  DQ2_A  = M_K_CPU0_SA_DQ<2>
  VSS65  = GND
  DQ3_A  = M_K_CPU0_SA_DQ<3>
  VSS66  = GND
  \dqs5_a_c||tdqs5_a_c||dqs5_a_t||tdqs5_a_t\  = M_K_CPU0_SA_DQS_DN<5>
  \dqs5_a_t||tdqs5_a_t\  = M_K_CPU0_SA_DQS_DP<5>
  VSS67  = GND
  DQ6_A  = M_K_CPU0_SA_DQ<6>
  VSS68  = GND
  DQ7_A  = M_K_CPU0_SA_DQ<7>
  VSS69  = GND
  DQ10_A  = M_K_CPU0_SA_DQ<10>
  VSS70  = GND
  DQ11_A  = M_K_CPU0_SA_DQ<11>
  VSS71  = GND
  \dqs6_a_c||tdqs6_a_c||dqs6_a_t||tdqs6_a_t\  = M_K_CPU0_SA_DQS_DN<6>
  \dqs6_a_t||tdqs6_a_t\  = M_K_CPU0_SA_DQS_DP<6>
  VSS72  = GND
  DQ14_A  = M_K_CPU0_SA_DQ<14>
  VSS73  = GND
  DQ15_A  = M_K_CPU0_SA_DQ<15>
  VSS74  = GND
  DQ18_A  = M_K_CPU0_SA_DQ<18>
  VSS75  = GND
  DQ19_A  = M_K_CPU0_SA_DQ<19>
  VSS76  = GND
  \dqs7_a_c||tdqs7_a_c\  = M_K_CPU0_SA_DQS_DN<7>
  \dqs7_a_t||tdqs7_a_t\  = M_K_CPU0_SA_DQS_DP<7>
  VSS77  = GND
  DQ22_A  = M_K_CPU0_SA_DQ<22>
  VSS78  = GND
  DQ23_A  = M_K_CPU0_SA_DQ<23>
  VSS79  = GND
  DQ26_A  = M_K_CPU0_SA_DQ<26>
  VSS80  = GND
  DQ27_A  = M_K_CPU0_SA_DQ<27>
  VSS81  = GND
  \dqs8_a_c||tdqs8_a_c\  = M_K_CPU0_SA_DQS_DN<8>
  \dqs8_a_t||tdqs8_a_t\  = M_K_CPU0_SA_DQS_DP<8>
  VSS82  = GND
  DQ30_A  = M_K_CPU0_SA_DQ<30>
  VSS83  = GND
  DQ31_A  = M_K_CPU0_SA_DQ<31>
  VSS84  = GND
  CB2_A  = M_K_CPU0_SA_CB<2>
  VSS85  = GND
  CB3_A  = M_K_CPU0_SA_CB<3>
  VSS86  = GND
  \dqs9_a_c||tdqs9_a_c\  = M_K_CPU0_SA_DQS_DN<9>
  \dqs9_a_t||tdqs9_a_t\  = M_K_CPU0_SA_DQS_DP<9>
  VSS87  = GND
  CB6_A  = M_K_CPU0_SA_CB<6>
  VSS88  = GND
  CB7_A  = M_K_CPU0_SA_CB<7>
  VSS89  = GND
  RESET_N  = M_K_CPU0_RESET_N
  VSS90  = GND
  CS1_A_N  = M_K_CPU0_SA_CS_N<1>
  VSS91  = GND
  CA1_A  = M_K_CPU0_SA_CA<1>
  VSS92  = GND
  CA3_A  = M_K_CPU0_SA_CA<3>
  VSS93  = GND
  CA5_A  = M_K_CPU0_SA_CA<5>
  VSS94  = GND
  CK_T  = M_K_CPU0_CLK_DP<0>
  CK_C  = M_K_CPU0_CLK_DN<0>
  VSS95  = GND
  RFU4  = NC
  CA1_B  = M_K_CPU0_SB_CA<1>
  VSS96  = GND
  CA3_B  = M_K_CPU0_SB_CA<3>
  VSS97  = GND
  CA5_B  = M_K_CPU0_SB_CA<5>
  VSS98  = GND
  PAR_B  = M_K_CPU0_SB_PAR
  VSS99  = GND
  CS1_B_N  = M_K_CPU0_SB_CS_N<1>
  VSS100  = GND
  RFU5  = NC
  RFU6  = NC
  VSS101  = GND
  CB6_B  = M_K_CPU0_SB_CB<6>
  VSS102  = GND
  CB7_B  = M_K_CPU0_SB_CB<7>
  VSS103  = GND
  DQS4_B_C  = M_K_CPU0_SB_DQS_DN<4>
  DQS4_B_T  = M_K_CPU0_SB_DQS_DP<4>
  VSS104  = GND
  CB2_B  = M_K_CPU0_SB_CB<2>
  VSS105  = GND
  CB3_B  = M_K_CPU0_SB_CB<3>
  VSS106  = GND
  DQ2_B  = M_K_CPU0_SB_DQ<2>
  VSS107  = GND
  DQ3_B  = M_K_CPU0_SB_DQ<3>
  VSS108  = GND
  \dqs5_b_c||tdqs5_b_c\  = M_K_CPU0_SB_DQS_DN<5>
  \dqs5_b_t||tdqs5_b_t\  = M_K_CPU0_SB_DQS_DP<5>
  VSS109  = GND
  DQ6_B  = M_K_CPU0_SB_DQ<6>
  VSS110  = GND
  DQ7_B  = M_K_CPU0_SB_DQ<7>
  VSS111  = GND
  DQ10_B  = M_K_CPU0_SB_DQ<10>
  VSS112  = GND
  DQ11_B  = M_K_CPU0_SB_DQ<11>
  VSS113  = GND
  \dqs6_b_c||tdqs6_b_c\  = M_K_CPU0_SB_DQS_DN<6>
  \dqs6_b_t||tdqs6_b_t\  = M_K_CPU0_SB_DQS_DP<6>
  VSS114  = GND
  DQ14_B  = M_K_CPU0_SB_DQ<14>
  VSS115  = GND
  DQ15_B  = M_K_CPU0_SB_DQ<15>
  VSS116  = GND
  DQ18_B  = M_K_CPU0_SB_DQ<18>
  VSS117  = GND
  DQ19_B  = M_K_CPU0_SB_DQ<19>
  VSS118  = GND
  \dqs7_b_c||tdqs7_b_c\  = M_K_CPU0_SB_DQS_DN<7>
  \dqs7_b_t||tdqs7_b_t\  = M_K_CPU0_SB_DQS_DP<7>
  VSS119  = GND
  DQ22_B  = M_K_CPU0_SB_DQ<22>
  VSS120  = GND
  DQ23_B  = M_K_CPU0_SB_DQ<23>
  VSS121  = GND
  DQ26_B  = M_K_CPU0_SB_DQ<26>
  VSS122  = GND
  DQ27_B  = M_K_CPU0_SB_DQ<27>
  VSS123  = GND
  \dqs8_b_c||tdqs8_b_c\  = M_K_CPU0_SB_DQS_DN<8>
  \dqs8_b_t||tdqs8_b_t\  = M_K_CPU0_SB_DQS_DP<8>
  VSS124  = GND
  DQ30_B  = M_K_CPU0_SB_DQ<30>
  VSS125  = GND
  DQ31_B  = M_K_CPU0_SB_DQ<31>
  VSS126  = GND
  G1  = GND
  G2  = GND
  G3  = GND

(kicad_pcb
	(version 20260206)
	(generator "pcbnew")
	(generator_version "10.0")
	(general
		(thickness 1.6)
		(legacy_teardrops no)
	)
	(paper "A4")
	(title_block
		(title "04192023_DAF0TMB3IC0_F0TG_MB_C_brd_V02_OCP.brd")
		(comment 1 "Grand Teton / footprint 2165 of 8354 (J20), pads 139-184 of 291")
	)
	(layers
		(0 "F.Cu" signal "TOP")
		(4 "In1.Cu" signal "GND")
		(6 "In2.Cu" signal "IN1")
		(8 "In3.Cu" signal "GND1")
		(10 "In4.Cu" signal "IN2")
		(12 "In5.Cu" signal "GND2")
		(14 "In6.Cu" signal "IN3")
		(16 "In7.Cu" signal "GND3")
		(18 "In8.Cu" signal "VCC")
		(20 "In9.Cu" signal "VCC1")
		(22 "In10.Cu" signal "GND4")
		(24 "In11.Cu" signal "IN4")
		(26 "In12.Cu" signal "GND5")
		(28 "In13.Cu" signal "IN5")
		(30 "In14.Cu" signal "GND6")
		(32 "In15.Cu" signal "IN6")
		(34 "In16.Cu" signal "GND7")
		(2 "B.Cu" signal "BOTTOM")
		(9 "F.Adhes" user "F.Adhesive")
		(11 "B.Adhes" user "B.Adhesive")
		(13 "F.Paste" user "Package Geometry/Pastemask Top")
		(15 "B.Paste" user "Package Geometry/Pastemask Bottom")
		(5 "F.SilkS" user "Ref Des/Silkscreen Top")
		(7 "B.SilkS" user "Ref Des/Silkscreen Bottom")
		(1 "F.Mask" user "Board Geometry/Soldermask Top")
		(3 "B.Mask" user "Board Geometry/Soldermask Bottom")
		(17 "Dwgs.User" user "User.Drawings")
		(19 "Cmts.User" user "User.Comments")
		(21 "Eco1.User" user "User.Eco1")
		(23 "Eco2.User" user "User.Eco2")
		(25 "Edge.Cuts" user "Board Geometry/Outline")
		(27 "Margin" user)
		(31 "F.CrtYd" user "Package Geometry/Place Bound Top")
		(29 "B.CrtYd" user "Package Geometry/Place Bound Bottom")
		(35 "F.Fab" user "Ref Des/Assembly Top")
		(33 "B.Fab" user "Ref Des/Assembly Bottom")
	)
	(footprint ""
		(layer "F.Cu")
		(at 444.594234 -255.560068 180)
		(property "Reference" "J20"
			(at 1.631188 -81.796128 0)
			(unlocked yes)
			(layer "F.SilkS")
			(effects
				(font
					(size 0.7874 0.5842)
					(thickness 0.1524)
				)
			)
		)
		(property "Value" ""
			(at 0 0 180)
			(layer "F.Fab")
			(effects
				(font
					(size 1.27 1.27)
				)
			)
		)
		(duplicate_pad_numbers_are_jumpers no)
		(pad "139" smd rect
			(at -2.050034 59.075066 90)
			(size 0.519938 1.4986)
			(layers "F.Cu" "F.Mask" "F.Paste")
			(net "GND")
		)
		(pad "140" smd rect
			(at -2.050034 59.92495 90)
			(size 0.519938 1.4986)
			(layers "F.Cu" "F.Mask" "F.Paste")
			(net "M_K_CPU0_SB_DQ<28>")
		)
		(pad "141" smd rect
			(at -2.050034 60.775088 90)
			(size 0.519938 1.4986)
			(layers "F.Cu" "F.Mask" "F.Paste")
			(net "GND")
		)
		(pad "142" smd rect
			(at -2.050034 61.624972 90)
			(size 0.519938 1.4986)
			(layers "F.Cu" "F.Mask" "F.Paste")
			(net "M_K_CPU0_SB_DQ<29>")
		)
		(pad "143" smd rect
			(at -2.050034 62.47511 90)
			(size 0.519938 1.4986)
			(layers "F.Cu" "F.Mask" "F.Paste")
			(net "GND")
		)
		(pad "144" smd rect
			(at -2.050034 63.324994 90)
			(size 0.519938 1.4986)
			(layers "F.Cu" "F.Mask" "F.Paste")
			(net "Net_2390")
		)
		(pad "145" smd rect
			(at 2.050034 -63.324994 90)
			(size 0.519938 1.4986)
			(layers "F.Cu" "F.Mask" "F.Paste")
			(net "P12V_MEM_CPU0")
		)
		(pad "146" smd rect
			(at 2.050034 -62.47511 90)
			(size 0.519938 1.4986)
			(layers "F.Cu" "F.Mask" "F.Paste")
			(net "P12V_MEM_CPU0")
		)
		(pad "147" smd rect
			(at 2.050034 -61.624972 90)
			(size 0.519938 1.4986)
			(layers "F.Cu" "F.Mask" "F.Paste")
			(net "PWRGD_CHK_CPU0_DIMM")
		)
		(pad "148" smd rect
			(at 2.050034 -60.775088 90)
			(size 0.519938 1.4986)
			(layers "F.Cu" "F.Mask" "F.Paste")
			(net "PD_CHK_CPU0_DIMM_SAA")
		)
		(pad "149" smd rect
			(at 2.050034 -59.92495 90)
			(size 0.519938 1.4986)
			(layers "F.Cu" "F.Mask" "F.Paste")
			(net "Net_2391")
		)
		(pad "150" smd rect
			(at 2.050034 -59.075066 90)
			(size 0.519938 1.4986)
			(layers "F.Cu" "F.Mask" "F.Paste")
			(net "Net_2392")
		)
		(pad "151" smd rect
			(at 2.050034 -58.224928 90)
			(size 0.519938 1.4986)
			(layers "F.Cu" "F.Mask" "F.Paste")
			(net "GND")
		)
		(pad "152" smd rect
			(at 2.050034 -57.375044 90)
			(size 0.519938 1.4986)
			(layers "F.Cu" "F.Mask" "F.Paste")
			(net "M_K_CPU0_SA_DQ<2>")
		)
		(pad "153" smd rect
			(at 2.050034 -56.524906 90)
			(size 0.519938 1.4986)
			(layers "F.Cu" "F.Mask" "F.Paste")
			(net "GND")
		)
		(pad "154" smd rect
			(at 2.050034 -55.675022 90)
			(size 0.519938 1.4986)
			(layers "F.Cu" "F.Mask" "F.Paste")
			(net "M_K_CPU0_SA_DQ<3>")
		)
		(pad "155" smd rect
			(at 2.050034 -54.824884 90)
			(size 0.519938 1.4986)
			(layers "F.Cu" "F.Mask" "F.Paste")
			(net "GND")
		)
		(pad "156" smd rect
			(at 2.050034 -53.975 90)
			(size 0.519938 1.4986)
			(layers "F.Cu" "F.Mask" "F.Paste")
			(net "M_K_CPU0_SA_DQS_DN<5>")
		)
		(pad "157" smd rect
			(at 2.050034 -53.125116 90)
			(size 0.519938 1.4986)
			(layers "F.Cu" "F.Mask" "F.Paste")
			(net "M_K_CPU0_SA_DQS_DP<5>")
		)
		(pad "158" smd rect
			(at 2.050034 -52.274978 90)
			(size 0.519938 1.4986)
			(layers "F.Cu" "F.Mask" "F.Paste")
			(net "GND")
		)
		(pad "159" smd rect
			(at 2.050034 -51.425094 90)
			(size 0.519938 1.4986)
			(layers "F.Cu" "F.Mask" "F.Paste")
			(net "M_K_CPU0_SA_DQ<6>")
		)
		(pad "160" smd rect
			(at 2.050034 -50.574956 90)
			(size 0.519938 1.4986)
			(layers "F.Cu" "F.Mask" "F.Paste")
			(net "GND")
		)
		(pad "161" smd rect
			(at 2.050034 -49.725072 90)
			(size 0.519938 1.4986)
			(layers "F.Cu" "F.Mask" "F.Paste")
			(net "M_K_CPU0_SA_DQ<7>")
		)
		(pad "162" smd rect
			(at 2.050034 -48.874934 90)
			(size 0.519938 1.4986)
			(layers "F.Cu" "F.Mask" "F.Paste")
			(net "GND")
		)
		(pad "163" smd rect
			(at 2.050034 -48.02505 90)
			(size 0.519938 1.4986)
			(layers "F.Cu" "F.Mask" "F.Paste")
			(net "M_K_CPU0_SA_DQ<10>")
		)
		(pad "164" smd rect
			(at 2.050034 -47.174912 90)
			(size 0.519938 1.4986)
			(layers "F.Cu" "F.Mask" "F.Paste")
			(net "GND")
		)
		(pad "165" smd rect
			(at 2.050034 -46.325028 90)
			(size 0.519938 1.4986)
			(layers "F.Cu" "F.Mask" "F.Paste")
			(net "M_K_CPU0_SA_DQ<11>")
		)
		(pad "166" smd rect
			(at 2.050034 -45.47489 90)
			(size 0.519938 1.4986)
			(layers "F.Cu" "F.Mask" "F.Paste")
			(net "GND")
		)
		(pad "167" smd rect
			(at 2.050034 -44.625006 90)
			(size 0.519938 1.4986)
			(layers "F.Cu" "F.Mask" "F.Paste")
			(net "M_K_CPU0_SA_DQS_DN<6>")
		)
		(pad "168" smd rect
			(at 2.050034 -43.775122 90)
			(size 0.519938 1.4986)
			(layers "F.Cu" "F.Mask" "F.Paste")
			(net "M_K_CPU0_SA_DQS_DP<6>")
		)
		(pad "169" smd rect
			(at 2.050034 -42.924984 90)
			(size 0.519938 1.4986)
			(layers "F.Cu" "F.Mask" "F.Paste")
			(net "GND")
		)
		(pad "170" smd rect
			(at 2.050034 -42.0751 90)
			(size 0.519938 1.4986)
			(layers "F.Cu" "F.Mask" "F.Paste")
			(net "M_K_CPU0_SA_DQ<14>")
		)
		(pad "171" smd rect
			(at 2.050034 -41.224962 90)
			(size 0.519938 1.4986)
			(layers "F.Cu" "F.Mask" "F.Paste")
			(net "GND")
		)
		(pad "172" smd rect
			(at 2.050034 -40.375078 90)
			(size 0.519938 1.4986)
			(layers "F.Cu" "F.Mask" "F.Paste")
			(net "M_K_CPU0_SA_DQ<15>")
		)
		(pad "173" smd rect
			(at 2.050034 -39.52494 90)
			(size 0.519938 1.4986)
			(layers "F.Cu" "F.Mask" "F.Paste")
			(net "GND")
		)
		(pad "174" smd rect
			(at 2.050034 -38.675056 90)
			(size 0.519938 1.4986)
			(layers "F.Cu" "F.Mask" "F.Paste")
			(net "M_K_CPU0_SA_DQ<18>")
		)
		(pad "175" smd rect
			(at 2.050034 -37.824918 90)
			(size 0.519938 1.4986)
			(layers "F.Cu" "F.Mask" "F.Paste")
			(net "GND")
		)
		(pad "176" smd rect
			(at 2.050034 -36.975034 90)
			(size 0.519938 1.4986)
			(layers "F.Cu" "F.Mask" "F.Paste")
			(net "M_K_CPU0_SA_DQ<19>")
		)
		(pad "177" smd rect
			(at 2.050034 -36.124896 90)
			(size 0.519938 1.4986)
			(layers "F.Cu" "F.Mask" "F.Paste")
			(net "GND")
		)
		(pad "178" smd rect
			(at 2.050034 -35.275012 90)
			(size 0.519938 1.4986)
			(layers "F.Cu" "F.Mask" "F.Paste")
			(net "M_K_CPU0_SA_DQS_DN<7>")
		)
		(pad "179" smd rect
			(at 2.050034 -34.425128 90)
			(size 0.519938 1.4986)
			(layers "F.Cu" "F.Mask" "F.Paste")
			(net "M_K_CPU0_SA_DQS_DP<7>")
		)
		(pad "180" smd rect
			(at 2.050034 -33.57499 90)
			(size 0.519938 1.4986)
			(layers "F.Cu" "F.Mask" "F.Paste")
			(net "GND")
		)
		(pad "181" smd rect
			(at 2.050034 -32.725106 90)
			(size 0.519938 1.4986)
			(layers "F.Cu" "F.Mask" "F.Paste")
			(net "M_K_CPU0_SA_DQ<22>")
		)
		(pad "182" smd rect
			(at 2.050034 -31.874968 90)
			(size 0.519938 1.4986)
			(layers "F.Cu" "F.Mask" "F.Paste")
			(net "GND")
		)
		(pad "183" smd rect
			(at 2.050034 -31.025084 90)
			(size 0.519938 1.4986)
			(layers "F.Cu" "F.Mask" "F.Paste")
			(net "M_K_CPU0_SA_DQ<23>")
		)
		(pad "184" smd rect
			(at 2.050034 -30.174946 90)
			(size 0.519938 1.4986)
			(layers "F.Cu" "F.Mask" "F.Paste")
			(net "GND")
		)
	)
)
